# SCM (Grand Teton) — schematic netlist excerpt (pin names and nets, part order shuffled) for the footprints in the layout excerpt that follows; sources: Cadence DE-HDL packaged netlist, KiCad conversion of 12092022_DA0F0TMDCD0_F0T_Management_Board_D_brd_V3_OCP.brd

D0  Q_LED  IC  pkg SMLF  page 47 : A = LED_POSTCODE_0_R ; C = GND

U2  FSA3357K8X  IC  pkg US8_0-5_2X2-3_EOL  page 30
  B0  = UART_BIC_DBG_TX
  B1  = UART_BMC_5_TXD_BUF1_R
  B2  = UART_BMC_1_TXD_R
  GND  = GND
  S2  = FM_UARTSW_LSB_N
  S1  = FM_UARTSW_MSB_N
  A  = SPA_SOUT_SW_BUF
  VCC  = P3V3_AUX

(kicad_pcb
	(version 20260206)
	(generator "pcbnew")
	(generator_version "10.0")
	(general
		(thickness 1.6)
		(legacy_teardrops no)
	)
	(paper "A4")
	(title_block
		(title "12092022_DA0F0TMDCD0_F0T_Management_Board_D_brd_V3_OCP.brd")
		(comment 1 "Grand Teton / footprints 222-223 of 1440")
	)
	(layers
		(0 "F.Cu" signal "TOP")
		(4 "In1.Cu" signal "GND")
		(6 "In2.Cu" signal "IN1")
		(8 "In3.Cu" signal "GND1")
		(10 "In4.Cu" signal "IN2")
		(12 "In5.Cu" signal "VCC")
		(14 "In6.Cu" signal "VCC1")
		(16 "In7.Cu" signal "IN3")
		(18 "In8.Cu" signal "GND2")
		(20 "In9.Cu" signal "IN4")
		(22 "In10.Cu" signal "GND3")
		(2 "B.Cu" signal "BOTTOM")
		(9 "F.Adhes" user "F.Adhesive")
		(11 "B.Adhes" user "B.Adhesive")
		(13 "F.Paste" user "Package Geometry/Pastemask Top")
		(15 "B.Paste" user "Package Geometry/Pastemask Bottom")
		(5 "F.SilkS" user "Ref Des/Silkscreen Top")
		(7 "B.SilkS" user "Ref Des/Silkscreen Bottom")
		(1 "F.Mask" user "Board Geometry/Soldermask Top")
		(3 "B.Mask" user "Board Geometry/Soldermask Bottom")
		(17 "Dwgs.User" user "User.Drawings")
		(19 "Cmts.User" user "User.Comments")
		(21 "Eco1.User" user "User.Eco1")
		(23 "Eco2.User" user "User.Eco2")
		(25 "Edge.Cuts" user "Board Geometry/Outline")
		(27 "Margin" user)
		(31 "F.CrtYd" user "Package Geometry/Place Bound Top")
		(29 "B.CrtYd" user "Package Geometry/Place Bound Bottom")
		(35 "F.Fab" user "Ref Des/Assembly Top")
		(33 "B.Fab" user "Ref Des/Assembly Bottom")
	)
	(footprint ""
		(layer "F.Cu")
		(at 78.907894 -28.196032 -90)
		(property "Reference" "D0"
			(at 2.237232 -7.427976 90)
			(unlocked yes)
			(layer "F.SilkS")
			(effects
				(font
					(size 0.7874 0.5842)
					(thickness 0.1524)
				)
				(justify left)
			)
		)
		(property "Value" ""
			(at 0 0 270)
			(layer "F.Fab")
			(effects
				(font
					(size 1.27 1.27)
				)
			)
		)
		(duplicate_pad_numbers_are_jumpers no)
		(fp_line
			(start -1.3208 0.5588)
			(end -1.3208 -0.5588)
			(stroke
				(width 0.1524)
				(type default)
			)
			(layer "F.SilkS")
		)
		(fp_line
			(start 1.3208 0.5588)
			(end -1.3208 0.5588)
			(stroke
				(width 0.1524)
				(type default)
			)
			(layer "F.SilkS")
		)
		(fp_line
			(start 1.6256 0.5588)
			(end 1.6256 -0.5588)
			(stroke
				(width 0.1524)
				(type default)
			)
			(layer "F.SilkS")
		)
		(fp_line
			(start 1.778 0.5588)
			(end 1.3208 0.5588)
			(stroke
				(width 0.1524)
				(type default)
			)
			(layer "F.SilkS")
		)
		(fp_line
			(start -1.3208 -0.5588)
			(end 1.3208 -0.5588)
			(stroke
				(width 0.1524)
				(type default)
			)
			(layer "F.SilkS")
		)
		(fp_line
			(start 1.3208 -0.5588)
			(end 1.3208 0.5588)
			(stroke
				(width 0.1524)
				(type default)
			)
			(layer "F.SilkS")
		)
		(fp_line
			(start 1.4732 -0.5588)
			(end 1.4732 0.5588)
			(stroke
				(width 0.1524)
				(type default)
			)
			(layer "F.SilkS")
		)
		(fp_line
			(start 1.778 -0.5588)
			(end 1.778 0.5588)
			(stroke
				(width 0.1524)
				(type default)
			)
			(layer "F.SilkS")
		)
		(fp_line
			(start 1.778 -0.5588)
			(end 1.3208 -0.5588)
			(stroke
				(width 0.1524)
				(type default)
			)
			(layer "F.SilkS")
		)
		(fp_line
			(start -1.235964 0.508)
			(end -1.1684 0.508)
			(stroke
				(width 0.1)
				(type default)
			)
			(layer "F.Fab")
		)
		(fp_line
			(start -1.1684 0.508)
			(end 1.1684 0.508)
			(stroke
				(width 0.1)
				(type default)
			)
			(layer "F.Fab")
		)
		(fp_line
			(start 1.1684 0.508)
			(end 1.236726 0.508)
			(stroke
				(width 0.1)
				(type default)
			)
			(layer "F.Fab")
		)
		(fp_line
			(start 1.236726 0.508)
			(end 1.236726 -0.508)
			(stroke
				(width 0.1)
				(type default)
			)
			(layer "F.Fab")
		)
		(fp_line
			(start -1.235964 -0.508)
			(end -1.235964 0.508)
			(stroke
				(width 0.1)
				(type default)
			)
			(layer "F.Fab")
		)
		(fp_line
			(start -1.1684 -0.508)
			(end -1.235964 -0.508)
			(stroke
				(width 0.1)
				(type default)
			)
			(layer "F.Fab")
		)
		(fp_line
			(start 1.1684 -0.508)
			(end -1.1684 -0.508)
			(stroke
				(width 0.1)
				(type default)
			)
			(layer "F.Fab")
		)
		(fp_line
			(start 1.236726 -0.508)
			(end 1.1684 -0.508)
			(stroke
				(width 0.1)
				(type default)
			)
			(layer "F.Fab")
		)
		(fp_text user "-"
			(at 1.654302 -0.867156 270)
			(unlocked yes)
			(layer "F.SilkS")
			(effects
				(font
					(size 1.905 1.4224)
					(thickness 0.1524)
				)
				(justify left)
			)
		)
		(fp_text user "+"
			(at -0.711454 -0.930402 90)
			(unlocked yes)
			(layer "F.SilkS")
			(effects
				(font
					(size 1.905 1.4224)
					(thickness 0.1524)
				)
				(justify left)
			)
		)
		(fp_text user "+"
			(at -2.5654 -0.24765 270)
			(unlocked yes)
			(layer "F.Fab")
			(effects
				(font
					(size 1.905 1.4224)
					(thickness 0.1524)
				)
				(justify left)
			)
		)
		(fp_text user "-"
			(at 1.524 -0.24765 270)
			(unlocked yes)
			(layer "F.Fab")
			(effects
				(font
					(size 1.905 1.4224)
					(thickness 0.1524)
				)
				(justify left)
			)
		)
		(pad "A" smd rect
			(at -0.750062 0 270)
			(size 0.8128 0.8128)
			(layers "F.Cu" "F.Mask" "F.Paste")
			(net "LED_POSTCODE_0_R")
		)
		(pad "C" smd rect
			(at 0.750062 0 270)
			(size 0.8128 0.8128)
			(layers "F.Cu" "F.Mask" "F.Paste")
			(net "GND")
		)
	)
	(footprint ""
		(layer "F.Cu")
		(at 24.9682 -62.3062 90)
		(property "Reference" "U2"
			(at -3.81 0.89027 90)
			(unlocked yes)
			(layer "F.SilkS")
			(effects
				(font
					(size 0.7874 0.5842)
					(thickness 0.1524)
				)
				(justify left)
			)
		)
		(property "Value" ""
			(at 0 0 90)
			(layer "F.Fab")
			(effects
				(font
					(size 1.27 1.27)
				)
			)
		)
		(duplicate_pad_numbers_are_jumpers no)
		(fp_line
			(start 0.8636 -1.050036)
			(end 0.542036 -1.050036)
			(stroke
				(width 0.1524)
				(type default)
			)
			(layer "F.SilkS")
		)
		(fp_line
			(start 0.542036 -1.050036)
			(end 0 -0.508)
			(stroke
				(width 0.1524)
				(type default)
			)
			(layer "F.SilkS")
		)
		(fp_line
			(start -0.542036 -1.050036)
			(end -0.8636 -1.050036)
			(stroke
				(width 0.1524)
				(type default)
			)
			(layer "F.SilkS")
		)
		(fp_line
			(start -0.8636 -1.050036)
			(end -0.8636 1.050036)
			(stroke
				(width 0.1524)
				(type default)
			)
			(layer "F.SilkS")
		)
		(fp_line
			(start 0 -0.508)
			(end -0.542036 -1.050036)
			(stroke
				(width 0.1524)
				(type default)
			)
			(layer "F.SilkS")
		)
		(fp_line
			(start 0.8636 1.050036)
			(end 0.8636 -1.050036)
			(stroke
				(width 0.1524)
				(type default)
			)
			(layer "F.SilkS")
		)
		(fp_line
			(start -0.8636 1.050036)
			(end 0.8636 1.050036)
			(stroke
				(width 0.1524)
				(type default)
			)
			(layer "F.SilkS")
		)
		(fp_poly
			(pts
				(xy -2.794 -1.258062) (xy -2.794 -0.242062) (xy -1.778 -0.750062)
			)
			(stroke
				(width 0)
				(type default)
			)
			(fill yes)
			(layer "F.SilkS")
		)
		(fp_line
			(start 1.199896 -1.050036)
			(end -1.199896 -1.050036)
			(stroke
				(width 0.1)
				(type default)
			)
			(layer "F.Fab")
		)
		(fp_line
			(start -1.199896 -1.050036)
			(end -1.199896 1.050036)
			(stroke
				(width 0.1)
				(type default)
			)
			(layer "F.Fab")
		)
		(fp_line
			(start 1.199896 1.050036)
			(end 1.199896 -1.050036)
			(stroke
				(width 0.1)
				(type default)
			)
			(layer "F.Fab")
		)
		(fp_line
			(start -1.199896 1.050036)
			(end 1.199896 1.050036)
			(stroke
				(width 0.1)
				(type default)
			)
			(layer "F.Fab")
		)
		(fp_poly
			(pts
				(xy -2.794 -1.258062) (xy -2.794 -0.242062) (xy -1.778 -0.750062)
			)
			(stroke
				(width 0)
				(type default)
			)
			(fill yes)
			(layer "F.Fab")
		)
		(pad "1" smd rect
			(at -1.35001 -0.750062)
			(size 0.2794 0.7112)
			(layers "F.Cu" "F.Mask" "F.Paste")
			(net "UART_BIC_DBG_TX")
		)
		(pad "2" smd rect
			(at -1.35001 -0.249936)
			(size 0.2794 0.7112)
			(layers "F.Cu" "F.Mask" "F.Paste")
			(net "UART_BMC_5_TXD_BUF1_R")
		)
		(pad "3" smd rect
			(at -1.35001 0.249936)
			(size 0.2794 0.7112)
			(layers "F.Cu" "F.Mask" "F.Paste")
			(net "UART_BMC_1_TXD_R")
		)
		(pad "4" smd rect
			(at -1.35001 0.750062)
			(size 0.2794 0.7112)
			(layers "F.Cu" "F.Mask" "F.Paste")
			(net "GND")
		)
		(pad "5" smd rect
			(at 1.35001 0.750062)
			(size 0.2794 0.7112)
			(layers "F.Cu" "F.Mask" "F.Paste")
			(net "FM_UARTSW_LSB_N")
		)
		(pad "6" smd rect
			(at 1.35001 0.249936)
			(size 0.2794 0.7112)
			(layers "F.Cu" "F.Mask" "F.Paste")
			(net "FM_UARTSW_MSB_N")
		)
		(pad "7" smd rect
			(at 1.35001 -0.249936)
			(size 0.2794 0.7112)
			(layers "F.Cu" "F.Mask" "F.Paste")
			(net "SPA_SOUT_SW_BUF")
		)
		(pad "8" smd rect
			(at 1.35001 -0.750062)
			(size 0.2794 0.7112)
			(layers "F.Cu" "F.Mask" "F.Paste")
			(net "P3V3_AUX")
		)
	)
)
